# BASEBOARD_FAB2 (Tioga Pass) — schematic netlist excerpt (pin names and nets, part order shuffled) for the footprints in the layout excerpt that follows; sources: Cadence DE-HDL packaged netlist, KiCad conversion of Wiwynn_Tioga_Pass_MB.brd

C1G29  CAP  0.22UF 16V 10% X7R  pkg 0402  page 224 : A = P5V_STBY ; B = GND
R4D11  RES  27.4 1% CHIP  pkg 0402  page 103 : A = CLK_100M_CPU1_BCLK2_R_DN ; B = CLK_100M_CPU1_BCLK2_DN
C1B19  CAP_A  0.1UF 16V 10% X7R  pkg 0402V  page 198 : A = P12V_FAN ; B = GND

(kicad_pcb
	(version 20260206)
	(generator "pcbnew")
	(generator_version "10.0")
	(general
		(thickness 1.6)
		(legacy_teardrops no)
	)
	(paper "A4")
	(title_block
		(title "Wiwynn_Tioga_Pass_MB.brd")
		(comment 1 "Tioga Pass / footprints 2145-2147 of 4770")
	)
	(layers
		(0 "F.Cu" signal "TOP")
		(4 "In1.Cu" signal "L2GND")
		(6 "In2.Cu" signal "L3")
		(8 "In3.Cu" signal "L4GND")
		(10 "In4.Cu" signal "L5")
		(12 "In5.Cu" signal "L6GND")
		(14 "In6.Cu" signal "L7VCC")
		(16 "In7.Cu" signal "L8VCC")
		(18 "In8.Cu" signal "L9GND")
		(20 "In9.Cu" signal "L10")
		(22 "In10.Cu" signal "L11GND")
		(24 "In11.Cu" signal "L12")
		(26 "In12.Cu" signal "L13GND")
		(2 "B.Cu" signal "BOTTOM")
		(9 "F.Adhes" user "F.Adhesive")
		(11 "B.Adhes" user "B.Adhesive")
		(13 "F.Paste" user "Package Geometry/Pastemask Top")
		(15 "B.Paste" user "Package Geometry/Pastemask Bottom")
		(5 "F.SilkS" user "Ref Des/Silkscreen Top")
		(7 "B.SilkS" user "Ref Des/Silkscreen Bottom")
		(1 "F.Mask" user "Board Geometry/Soldermask Top")
		(3 "B.Mask" user "Board Geometry/Soldermask Bottom")
		(17 "Dwgs.User" user "User.Drawings")
		(19 "Cmts.User" user "User.Comments")
		(21 "Eco1.User" user "User.Eco1")
		(23 "Eco2.User" user "User.Eco2")
		(25 "Edge.Cuts" user "Board Geometry/Outline")
		(27 "Margin" user)
		(31 "F.CrtYd" user "Package Geometry/Place Bound Top")
		(29 "B.CrtYd" user "Package Geometry/Place Bound Bottom")
		(35 "F.Fab" user "Ref Des/Assembly Top")
		(33 "B.Fab" user "Ref Des/Assembly Bottom")
	)
	(footprint ""
		(layer "F.Cu")
		(at 4.29895 -13.642594 90)
		(property "Reference" "C1G29"
			(at 0 0 90)
			(layer "F.SilkS")
			(hide yes)
			(effects
				(font
					(size 1.27 1.27)
				)
			)
		)
		(property "Value" ""
			(at 0 0 90)
			(layer "F.Fab")
			(effects
				(font
					(size 1.27 1.27)
				)
			)
		)
		(duplicate_pad_numbers_are_jumpers no)
		(fp_rect
			(start 0.3048 0.9906)
			(end -0.3048 -0.1016)
			(stroke
				(width 0)
				(type default)
			)
			(fill no)
			(layer "F.CrtYd")
		)
		(fp_line
			(start 0.3048 -0.1016)
			(end -0.3048 -0.1016)
			(stroke
				(width 0.1)
				(type default)
			)
			(layer "F.Fab")
		)
		(fp_line
			(start -0.3048 -0.1016)
			(end -0.3048 0.9906)
			(stroke
				(width 0.1)
				(type default)
			)
			(layer "F.Fab")
		)
		(fp_line
			(start 0.3048 0.9906)
			(end 0.3048 -0.1016)
			(stroke
				(width 0.1)
				(type default)
			)
			(layer "F.Fab")
		)
		(fp_line
			(start -0.3048 0.9906)
			(end 0.3048 0.9906)
			(stroke
				(width 0.1)
				(type default)
			)
			(layer "F.Fab")
		)
		(pad "1" smd rect
			(at 0 0 90)
			(size 0.508 0.508)
			(layers "F.Cu" "F.Mask" "F.Paste")
			(net "P5V_STBY")
		)
		(pad "2" smd rect
			(at 0 0.889 90)
			(size 0.508 0.508)
			(layers "F.Cu" "F.Mask" "F.Paste")
			(net "GND")
		)
		(zone
			(layer "F.Cu")
			(hatch none 0.5)
			(connect_pads
				(clearance 0)
			)
			(min_thickness 0.25)
			(keepout
				(tracks not_allowed)
				(vias allowed)
				(pads allowed)
				(copperpour not_allowed)
				(footprints allowed)
			)
			(placement
				(enabled no)
				(sheetname "")
			)
			(fill
				(thermal_gap 0.5)
				(thermal_bridge_width 0.5)
				(island_removal_mode 0)
			)
			(polygon
				(pts
					(xy 4.93395 -13.896594) (xy 4.55295 -13.896594) (xy 4.55295 -13.388594) (xy 4.93395 -13.388594)
				)
			)
		)
		(zone
			(layer "F.Cu")
			(hatch none 0.5)
			(connect_pads
				(clearance 0)
			)
			(min_thickness 0.25)
			(keepout
				(tracks allowed)
				(vias not_allowed)
				(pads allowed)
				(copperpour not_allowed)
				(footprints allowed)
			)
			(placement
				(enabled no)
				(sheetname "")
			)
			(fill
				(thermal_gap 0.5)
				(thermal_bridge_width 0.5)
				(island_removal_mode 0)
			)
			(polygon
				(pts
					(xy 4.93395 -13.896594) (xy 4.55295 -13.896594) (xy 4.55295 -13.388594) (xy 4.93395 -13.388594)
				)
			)
		)
	)
	(footprint ""
		(layer "F.Cu")
		(at 7.69747 -110.891828 90)
		(property "Reference" "C1B19"
			(at -0.8382 -0.67818 90)
			(unlocked yes)
			(layer "F.SilkS")
			(effects
				(font
					(size 0.4064 0.254)
					(thickness 0.1524)
				)
				(justify left)
			)
		)
		(property "Value" ""
			(at 0 0 90)
			(layer "F.Fab")
			(effects
				(font
					(size 1.27 1.27)
				)
			)
		)
		(duplicate_pad_numbers_are_jumpers no)
		(fp_poly
			(pts
				(xy 0.3048 -0.1016) (xy 0.3048 0.9906) (xy -0.3048 0.9906) (xy -0.3048 -0.1016)
			)
			(stroke
				(width 0)
				(type default)
			)
			(fill no)
			(layer "F.CrtYd")
		)
		(fp_line
			(start 0.3048 -0.1016)
			(end -0.3048 -0.1016)
			(stroke
				(width 0.1)
				(type default)
			)
			(layer "F.Fab")
		)
		(fp_line
			(start -0.3048 -0.1016)
			(end -0.3048 0.9906)
			(stroke
				(width 0.1)
				(type default)
			)
			(layer "F.Fab")
		)
		(fp_line
			(start 0.3048 0.9906)
			(end 0.3048 -0.1016)
			(stroke
				(width 0.1)
				(type default)
			)
			(layer "F.Fab")
		)
		(fp_line
			(start -0.3048 0.9906)
			(end 0.3048 0.9906)
			(stroke
				(width 0.1)
				(type default)
			)
			(layer "F.Fab")
		)
		(pad "1" smd rect
			(at 0 0 90)
			(size 0.508 0.508)
			(layers "F.Cu" "F.Mask" "F.Paste")
			(net "P12V_FAN")
		)
		(pad "2" smd rect
			(at 0 0.889 90)
			(size 0.508 0.508)
			(layers "F.Cu" "F.Mask" "F.Paste")
			(net "GND")
		)
		(zone
			(layer "F.Cu")
			(hatch none 0.5)
			(connect_pads
				(clearance 0)
			)
			(min_thickness 0.25)
			(keepout
				(tracks allowed)
				(vias not_allowed)
				(pads allowed)
				(copperpour not_allowed)
				(footprints allowed)
			)
			(placement
				(enabled no)
				(sheetname "")
			)
			(fill
				(thermal_gap 0.5)
				(thermal_bridge_width 0.5)
				(island_removal_mode 0)
			)
			(polygon
				(pts
					(xy 7.95147 -110.637828) (xy 7.95147 -111.145828) (xy 8.33247 -111.145828) (xy 8.33247 -110.637828)
				)
			)
		)
		(zone
			(layer "F.Cu")
			(hatch none 0.5)
			(connect_pads
				(clearance 0)
			)
			(min_thickness 0.25)
			(keepout
				(tracks not_allowed)
				(vias allowed)
				(pads allowed)
				(copperpour not_allowed)
				(footprints allowed)
			)
			(placement
				(enabled no)
				(sheetname "")
			)
			(fill
				(thermal_gap 0.5)
				(thermal_bridge_width 0.5)
				(island_removal_mode 0)
			)
			(polygon
				(pts
					(xy 8.33247 -110.637828) (xy 8.33247 -111.145828) (xy 7.95147 -111.145828) (xy 7.95147 -110.637828)
				)
			)
		)
	)
	(footprint ""
		(layer "F.Cu")
		(at 163.576 -84.328 -90)
		(property "Reference" "R4D11"
			(at 0 0 270)
			(layer "F.SilkS")
			(hide yes)
			(effects
				(font
					(size 1.27 1.27)
				)
			)
		)
		(property "Value" ""
			(at 0 0 270)
			(layer "F.Fab")
			(effects
				(font
					(size 1.27 1.27)
				)
			)
		)
		(duplicate_pad_numbers_are_jumpers no)
		(fp_poly
			(pts
				(xy -0.2794 -0.1016) (xy 0.2794 -0.1016) (xy 0.2794 0.9906) (xy -0.2794 0.9906)
			)
			(stroke
				(width 0)
				(type default)
			)
			(fill no)
			(layer "F.CrtYd")
		)
		(fp_line
			(start -0.2794 0.9906)
			(end 0.2794 0.9906)
			(stroke
				(width 0.1)
				(type default)
			)
			(layer "F.Fab")
		)
		(fp_line
			(start 0.2794 0.9906)
			(end 0.2794 -0.1016)
			(stroke
				(width 0.1)
				(type default)
			)
			(layer "F.Fab")
		)
		(fp_line
			(start -0.2794 -0.1016)
			(end -0.2794 0.9906)
			(stroke
				(width 0.1)
				(type default)
			)
			(layer "F.Fab")
		)
		(fp_line
			(start 0.2794 -0.1016)
			(end -0.2794 -0.1016)
			(stroke
				(width 0.1)
				(type default)
			)
			(layer "F.Fab")
		)
		(pad "1" smd rect
			(at 0 0 270)
			(size 0.508 0.508)
			(layers "F.Cu" "F.Mask" "F.Paste")
			(net "CLK_100M_CPU1_BCLK2_R_DN")
		)
		(pad "2" smd rect
			(at 0 0.889 270)
			(size 0.508 0.508)
			(layers "F.Cu" "F.Mask" "F.Paste")
			(net "CLK_100M_CPU1_BCLK2_DN")
		)
		(zone
			(layer "F.Cu")
			(hatch none 0.5)
			(connect_pads
				(clearance 0)
			)
			(min_thickness 0.25)
			(keepout
				(tracks not_allowed)
				(vias allowed)
				(pads allowed)
				(copperpour not_allowed)
				(footprints allowed)
			)
			(placement
				(enabled no)
				(sheetname "")
			)
			(fill
				(thermal_gap 0.5)
				(thermal_bridge_width 0.5)
				(island_removal_mode 0)
			)
			(polygon
				(pts
					(xy 162.941 -84.582) (xy 162.941 -84.074) (xy 163.322 -84.074) (xy 163.322 -84.582)
				)
			)
		)
		(zone
			(layer "F.Cu")
			(hatch none 0.5)
			(connect_pads
				(clearance 0)
			)
			(min_thickness 0.25)
			(keepout
				(tracks allowed)
				(vias not_allowed)
				(pads allowed)
				(copperpour not_allowed)
				(footprints allowed)
			)
			(placement
				(enabled no)
				(sheetname "")
			)
			(fill
				(thermal_gap 0.5)
				(thermal_bridge_width 0.5)
				(island_removal_mode 0)
			)
			(polygon
				(pts
					(xy 163.322 -84.582) (xy 163.322 -84.074) (xy 162.941 -84.074) (xy 162.941 -84.582)
				)
			)
		)
	)
)
